(kicad_pcb
	(version 20221018)
	(generator pcbnew)
	(general
    (thickness 1.518)
  )
	(paper "A4")
	(title_block
    (title "Kria K26 Devboard")
    (date "2024-03-26")
    (rev "1.2.5")
    (comment 1 "www.antmicro.com")
    (comment 2 "Antmicro Ltd.")
		(comment 9 "footprints 479-488 of 660")
	)
	(layers
    (0 "F.Cu" mixed)
    (1 "In1.Cu" power)
    (2 "In2.Cu" mixed)
    (3 "In3.Cu" power)
    (4 "In4.Cu" mixed)
    (5 "In5.Cu" power)
    (6 "In6.Cu" mixed)
    (31 "B.Cu" power)
    (32 "B.Adhes" user "B.Adhesive")
    (33 "F.Adhes" user "F.Adhesive")
    (34 "B.Paste" user)
    (35 "F.Paste" user)
    (36 "B.SilkS" user "B.Silkscreen")
    (37 "F.SilkS" user "F.Silkscreen")
    (38 "B.Mask" user)
    (39 "F.Mask" user)
    (40 "Dwgs.User" user "User.Drawings")
    (41 "Cmts.User" user "User.Comments")
    (42 "Eco1.User" user "User.Eco1")
    (43 "Eco2.User" user "User.Eco2")
    (44 "Edge.Cuts" user)
    (45 "Margin" user)
    (46 "B.CrtYd" user "B.Courtyard")
    (47 "F.CrtYd" user "F.Courtyard")
    (48 "B.Fab" user)
    (49 "F.Fab" user)
  )
	(footprint "kria-k26-devboard-footprints:R_0402_1005Metric" (layer "B.Cu")
    (at 116.556942 87.4 180)
    (descr "Resistor SMD 0402")
    (tags "resistor SMD 0402")
    (property "Author" "Antmicro")
    (property "License" "Apache-2.0")
    (property "MPN" "CR0402-FX-2003GLF")
    (property "Manufacturer" "Bourns")
    (property "Sheetfile" "usb.kicad_sch")
    (property "Sheetname" "USB")
    (property "Tolerance" "1%")
    (property "Val" "200k")
    (property "ki_description" "200k resistor in 0402 package with 1% tolerance")
    (attr smd)
    (fp_text reference "R41" (at 0.926942 -0.35) (layer "B.SilkS")
        (effects (font (size 0.7 0.7) (thickness 0.15)) (justify left bottom mirror))
    )
    (fp_text value "R_200k_0402" (at 0 -1.4) (layer "B.Fab") hide
        (effects (font (size 0.7 0.7) (thickness 0.15)) (justify left bottom mirror))
    )
    (fp_text user "Author: Antmicro" (at -0.95 -4.169) (layer "B.Fab") hide
        (effects (font (size 0.7 0.7) (thickness 0.15)) (justify left bottom mirror))
    )
    (fp_text user "${REFERENCE}" (at -0.95 -3.168) (layer "B.Fab") hide
        (effects (font (size 0.7 0.7) (thickness 0.15)) (justify left bottom mirror))
    )
    (fp_text user "License: Apache-2.0" (at -0.95 -5.169) (layer "B.Fab") hide
        (effects (font (size 0.7 0.7) (thickness 0.15)) (justify left bottom mirror))
    )
    (fp_rect (start -0.93 0.47) (end 0.93 -0.47)
      (stroke (width 0.05) (type solid)) (fill none) (layer "B.CrtYd"))
    (fp_rect (start -0.5 0.25) (end 0.5 -0.25)
      (stroke (width 0.15) (type solid)) (fill none) (layer "B.Fab"))
    (pad "1" smd roundrect (at -0.485 0 180) (size 0.59 0.64) (layers "B.Cu" "B.Paste" "B.Mask") (roundrect_rratio 0.25)
      (net 1 "GND") (pintype "passive"))
    (pad "2" smd roundrect (at 0.485 0 180) (size 0.59 0.64) (layers "B.Cu" "B.Paste" "B.Mask") (roundrect_rratio 0.25)
      (net 644 "Net-(U17-SPI_CE_N{slash}CFG_NON_REM{slash}PF20)") (pintype "passive"))
  )
	(footprint "kria-k26-devboard-footprints:C_0402_1005Metric" (layer "B.Cu")
    (at 139.370389 113.357609)
    (descr "Capacitor SMD 0402")
    (tags "capacitor SMD 0402")
    (property "Author" "Antmicro")
    (property "Dielectric" "X5R")
    (property "License" "Apache-2.0")
    (property "MPN" "GRM155R61H104KE14D")
    (property "Manufacturer" "Murata")
    (property "Sheetfile" "debug.kicad_sch")
    (property "Sheetname" "Debug and JTAG")
    (property "Val" "100n")
    (property "Voltage" "50V")
    (property "ki_description" " ")
    (attr smd)
    (fp_text reference "C157" (at 3.799611 0.412391 180) (layer "B.SilkS")
        (effects (font (size 0.7 0.7) (thickness 0.15)) (justify left bottom mirror))
    )
    (fp_text value "C_100n_0402" (at 0 -1.4 180) (layer "B.Fab") hide
        (effects (font (size 0.7 0.7) (thickness 0.15)) (justify left bottom mirror))
    )
    (fp_text user "${REFERENCE}" (at -0.932 -3.168 180) (layer "B.Fab") hide
        (effects (font (size 0.7 0.7) (thickness 0.15)) (justify left bottom mirror))
    )
    (fp_text user "License: Apache-2.0" (at -0.932 -5.17 180) (layer "B.Fab") hide
        (effects (font (size 0.7 0.7) (thickness 0.15)) (justify left bottom mirror))
    )
    (fp_text user "Author: Antmicro" (at -0.932 -4.17 180) (layer "B.Fab") hide
        (effects (font (size 0.7 0.7) (thickness 0.15)) (justify left bottom mirror))
    )
    (fp_rect (start -0.94 0.47) (end 0.94 -0.47)
      (stroke (width 0.05) (type solid)) (fill none) (layer "B.CrtYd"))
    (fp_rect (start -0.499 0.249) (end 0.499 -0.249)
      (stroke (width 0.15) (type solid)) (fill none) (layer "B.Fab"))
    (pad "1" smd roundrect (at -0.484 0) (size 0.59 0.64) (layers "B.Cu" "B.Paste" "B.Mask") (roundrect_rratio 0.25)
      (net 138 "/Debug and JTAG/USB_3V3") (pintype "passive"))
    (pad "2" smd roundrect (at 0.484 0) (size 0.59 0.64) (layers "B.Cu" "B.Paste" "B.Mask") (roundrect_rratio 0.25)
      (net 1 "GND") (pintype "passive"))
  )
	(footprint "kria-k26-devboard-footprints:C_0402_1005Metric" (layer "B.Cu")
    (at 143.84 125.45 180)
    (descr "Capacitor SMD 0402")
    (tags "capacitor SMD 0402")
    (property "Author" "Antmicro")
    (property "Dielectric" "X5R")
    (property "License" "Apache-2.0")
    (property "MPN" "GRM155R61H104KE14D")
    (property "Manufacturer" "Murata")
    (property "Sheetfile" "debug.kicad_sch")
    (property "Sheetname" "Debug and JTAG")
    (property "Val" "100n")
    (property "Voltage" "50V")
    (property "ki_description" " ")
    (attr smd)
    (fp_text reference "C164" (at -3.745313 -0.316087) (layer "B.SilkS")
        (effects (font (size 0.7 0.7) (thickness 0.15)) (justify left bottom mirror))
    )
    (fp_text value "C_100n_0402" (at 0 -1.4) (layer "B.Fab") hide
        (effects (font (size 0.7 0.7) (thickness 0.15)) (justify left bottom mirror))
    )
    (fp_text user "License: Apache-2.0" (at -0.932 -5.17) (layer "B.Fab") hide
        (effects (font (size 0.7 0.7) (thickness 0.15)) (justify left bottom mirror))
    )
    (fp_text user "Author: Antmicro" (at -0.932 -4.17) (layer "B.Fab") hide
        (effects (font (size 0.7 0.7) (thickness 0.15)) (justify left bottom mirror))
    )
    (fp_text user "${REFERENCE}" (at -0.932 -3.168) (layer "B.Fab") hide
        (effects (font (size 0.7 0.7) (thickness 0.15)) (justify left bottom mirror))
    )
    (fp_rect (start -0.94 0.47) (end 0.94 -0.47)
      (stroke (width 0.05) (type solid)) (fill none) (layer "B.CrtYd"))
    (fp_rect (start -0.499 0.249) (end 0.499 -0.249)
      (stroke (width 0.15) (type solid)) (fill none) (layer "B.Fab"))
    (pad "1" smd roundrect (at -0.484 0 180) (size 0.59 0.64) (layers "B.Cu" "B.Paste" "B.Mask") (roundrect_rratio 0.25)
      (net 138 "/Debug and JTAG/USB_3V3") (pintype "passive"))
    (pad "2" smd roundrect (at 0.484 0 180) (size 0.59 0.64) (layers "B.Cu" "B.Paste" "B.Mask") (roundrect_rratio 0.25)
      (net 1 "GND") (pintype "passive"))
  )
	(footprint "kria-k26-devboard-footprints:C_0402_1005Metric" (layer "B.Cu")
    (at 140.671787 126.524767 180)
    (descr "Capacitor SMD 0402")
    (tags "capacitor SMD 0402")
    (property "Author" "Antmicro")
    (property "Dielectric" "X5R")
    (property "License" "Apache-2.0")
    (property "MPN" "GRM155R61H104KE14D")
    (property "Manufacturer" "Murata")
    (property "Sheetfile" "debug.kicad_sch")
    (property "Sheetname" "Debug and JTAG")
    (property "Val" "100n")
    (property "Voltage" "50V")
    (property "ki_description" " ")
    (attr smd)
    (fp_text reference "C165" (at 0.895609 -0.343402) (layer "B.SilkS")
        (effects (font (size 0.7 0.7) (thickness 0.15)) (justify left bottom mirror))
    )
    (fp_text value "C_100n_0402" (at 0 -1.4) (layer "B.Fab") hide
        (effects (font (size 0.7 0.7) (thickness 0.15)) (justify left bottom mirror))
    )
    (fp_text user "License: Apache-2.0" (at -0.932 -5.17) (layer "B.Fab") hide
        (effects (font (size 0.7 0.7) (thickness 0.15)) (justify left bottom mirror))
    )
    (fp_text user "Author: Antmicro" (at -0.932 -4.17) (layer "B.Fab") hide
        (effects (font (size 0.7 0.7) (thickness 0.15)) (justify left bottom mirror))
    )
    (fp_text user "${REFERENCE}" (at -0.932 -3.168) (layer "B.Fab") hide
        (effects (font (size 0.7 0.7) (thickness 0.15)) (justify left bottom mirror))
    )
    (fp_rect (start -0.94 0.47) (end 0.94 -0.47)
      (stroke (width 0.05) (type solid)) (fill none) (layer "B.CrtYd"))
    (fp_rect (start -0.499 0.249) (end 0.499 -0.249)
      (stroke (width 0.15) (type solid)) (fill none) (layer "B.Fab"))
    (pad "1" smd roundrect (at -0.484 0 180) (size 0.59 0.64) (layers "B.Cu" "B.Paste" "B.Mask") (roundrect_rratio 0.25)
      (net 138 "/Debug and JTAG/USB_3V3") (pintype "passive"))
    (pad "2" smd roundrect (at 0.484 0 180) (size 0.59 0.64) (layers "B.Cu" "B.Paste" "B.Mask") (roundrect_rratio 0.25)
      (net 1 "GND") (pintype "passive"))
  )
	(footprint "kria-k26-devboard-footprints:C_0402_1005Metric" (layer "B.Cu")
    (at 140.665609 125.576598 180)
    (descr "Capacitor SMD 0402")
    (tags "capacitor SMD 0402")
    (property "Author" "Antmicro")
    (property "Dielectric" "X5R")
    (property "License" "Apache-2.0")
    (property "MPN" "GRM155R61H104KE14D")
    (property "Manufacturer" "Murata")
    (property "Sheetfile" "debug.kicad_sch")
    (property "Sheetname" "Debug and JTAG")
    (property "Val" "100n")
    (property "Voltage" "50V")
    (property "ki_description" " ")
    (attr smd)
    (fp_text reference "C167" (at 0.895609 -0.343402) (layer "B.SilkS")
        (effects (font (size 0.7 0.7) (thickness 0.15)) (justify left bottom mirror))
    )
    (fp_text value "C_100n_0402" (at 0 -1.4) (layer "B.Fab") hide
        (effects (font (size 0.7 0.7) (thickness 0.15)) (justify left bottom mirror))
    )
    (fp_text user "License: Apache-2.0" (at -0.932 -5.17) (layer "B.Fab") hide
        (effects (font (size 0.7 0.7) (thickness 0.15)) (justify left bottom mirror))
    )
    (fp_text user "${REFERENCE}" (at -0.932 -3.168) (layer "B.Fab") hide
        (effects (font (size 0.7 0.7) (thickness 0.15)) (justify left bottom mirror))
    )
    (fp_text user "Author: Antmicro" (at -0.932 -4.17) (layer "B.Fab") hide
        (effects (font (size 0.7 0.7) (thickness 0.15)) (justify left bottom mirror))
    )
    (fp_rect (start -0.94 0.47) (end 0.94 -0.47)
      (stroke (width 0.05) (type solid)) (fill none) (layer "B.CrtYd"))
    (fp_rect (start -0.499 0.249) (end 0.499 -0.249)
      (stroke (width 0.15) (type solid)) (fill none) (layer "B.Fab"))
    (pad "1" smd roundrect (at -0.484 0 180) (size 0.59 0.64) (layers "B.Cu" "B.Paste" "B.Mask") (roundrect_rratio 0.25)
      (net 138 "/Debug and JTAG/USB_3V3") (pintype "passive"))
    (pad "2" smd roundrect (at 0.484 0 180) (size 0.59 0.64) (layers "B.Cu" "B.Paste" "B.Mask") (roundrect_rratio 0.25)
      (net 1 "GND") (pintype "passive"))
  )
	(footprint "kria-k26-devboard-footprints:C_0402_1005Metric" (layer "B.Cu")
    (at 143.844687 126.403913 180)
    (descr "Capacitor SMD 0402")
    (tags "capacitor SMD 0402")
    (property "Author" "Antmicro")
    (property "Dielectric" "X5R")
    (property "License" "Apache-2.0")
    (property "MPN" "GRM155R61H104KE14D")
    (property "Manufacturer" "Murata")
    (property "Sheetfile" "debug.kicad_sch")
    (property "Sheetname" "Debug and JTAG")
    (property "Val" "100n")
    (property "Voltage" "50V")
    (property "ki_description" " ")
    (attr smd)
    (fp_text reference "C166" (at -3.745313 -0.316087) (layer "B.SilkS")
        (effects (font (size 0.7 0.7) (thickness 0.15)) (justify left bottom mirror))
    )
    (fp_text value "C_100n_0402" (at 0 -1.4) (layer "B.Fab") hide
        (effects (font (size 0.7 0.7) (thickness 0.15)) (justify left bottom mirror))
    )
    (fp_text user "Author: Antmicro" (at -0.932 -4.17) (layer "B.Fab") hide
        (effects (font (size 0.7 0.7) (thickness 0.15)) (justify left bottom mirror))
    )
    (fp_text user "License: Apache-2.0" (at -0.932 -5.17) (layer "B.Fab") hide
        (effects (font (size 0.7 0.7) (thickness 0.15)) (justify left bottom mirror))
    )
    (fp_text user "${REFERENCE}" (at -0.932 -3.168) (layer "B.Fab") hide
        (effects (font (size 0.7 0.7) (thickness 0.15)) (justify left bottom mirror))
    )
    (fp_rect (start -0.94 0.47) (end 0.94 -0.47)
      (stroke (width 0.05) (type solid)) (fill none) (layer "B.CrtYd"))
    (fp_rect (start -0.499 0.249) (end 0.499 -0.249)
      (stroke (width 0.15) (type solid)) (fill none) (layer "B.Fab"))
    (pad "1" smd roundrect (at -0.484 0 180) (size 0.59 0.64) (layers "B.Cu" "B.Paste" "B.Mask") (roundrect_rratio 0.25)
      (net 17 "PS_1V8") (pintype "passive"))
    (pad "2" smd roundrect (at 0.484 0 180) (size 0.59 0.64) (layers "B.Cu" "B.Paste" "B.Mask") (roundrect_rratio 0.25)
      (net 1 "GND") (pintype "passive"))
  )
	(footprint "kria-k26-devboard-footprints:C_0402_1005Metric" (layer "B.Cu")
    (at 140.471787 130.406137 90)
    (descr "Capacitor SMD 0402")
    (tags "capacitor SMD 0402")
    (property "Author" "Antmicro")
    (property "Dielectric" "X5R")
    (property "License" "Apache-2.0")
    (property "MPN" "GRM155R61H104KE14D")
    (property "Manufacturer" "Murata")
    (property "Sheetfile" "debug.kicad_sch")
    (property "Sheetname" "Debug and JTAG")
    (property "Val" "100n")
    (property "Voltage" "50V")
    (property "ki_description" " ")
    (attr smd)
    (fp_text reference "C170" (at 1.206137 1.398213 270) (layer "B.SilkS")
        (effects (font (size 0.7 0.7) (thickness 0.15)) (justify left bottom mirror))
    )
    (fp_text value "C_100n_0402" (at 0 -1.4 270) (layer "B.Fab") hide
        (effects (font (size 0.7 0.7) (thickness 0.15)) (justify left bottom mirror))
    )
    (fp_text user "${REFERENCE}" (at -0.932 -3.168 270) (layer "B.Fab") hide
        (effects (font (size 0.7 0.7) (thickness 0.15)) (justify left bottom mirror))
    )
    (fp_text user "License: Apache-2.0" (at -0.932 -5.17 270) (layer "B.Fab") hide
        (effects (font (size 0.7 0.7) (thickness 0.15)) (justify left bottom mirror))
    )
    (fp_text user "Author: Antmicro" (at -0.932 -4.17 270) (layer "B.Fab") hide
        (effects (font (size 0.7 0.7) (thickness 0.15)) (justify left bottom mirror))
    )
    (fp_rect (start -0.94 0.47) (end 0.94 -0.47)
      (stroke (width 0.05) (type solid)) (fill none) (layer "B.CrtYd"))
    (fp_rect (start -0.499 0.249) (end 0.499 -0.249)
      (stroke (width 0.15) (type solid)) (fill none) (layer "B.Fab"))
    (pad "1" smd roundrect (at -0.484 0 90) (size 0.59 0.64) (layers "B.Cu" "B.Paste" "B.Mask") (roundrect_rratio 0.25)
      (net 138 "/Debug and JTAG/USB_3V3") (pintype "passive"))
    (pad "2" smd roundrect (at 0.484 0 90) (size 0.59 0.64) (layers "B.Cu" "B.Paste" "B.Mask") (roundrect_rratio 0.25)
      (net 1 "GND") (pintype "passive"))
  )
	(footprint "kria-k26-devboard-footprints:R_0402_1005Metric" (layer "B.Cu")
    (at 118.85 92.7 -90)
    (descr "Resistor SMD 0402")
    (tags "resistor SMD 0402")
    (property "Author" "Antmicro")
    (property "License" "Apache-2.0")
    (property "MPN" "CR0402-FX-4992GLF")
    (property "Manufacturer" "Bourns")
    (property "Sheetfile" "usb.kicad_sch")
    (property "Sheetname" "USB")
    (property "Tolerance" "1%")
    (property "Val" "49k9")
    (property "ki_description" "49k9 resistor in 0402 package with 1% tolerance")
    (attr smd)
    (fp_text reference "R39" (at 0.83 -0.41 90) (layer "B.SilkS")
        (effects (font (size 0.7 0.7) (thickness 0.15)) (justify left bottom mirror))
    )
    (fp_text value "R_49k9_0402" (at 0 -1.4 90) (layer "B.Fab") hide
        (effects (font (size 0.7 0.7) (thickness 0.15)) (justify left bottom mirror))
    )
    (fp_text user "License: Apache-2.0" (at -0.95 -5.169 90) (layer "B.Fab") hide
        (effects (font (size 0.7 0.7) (thickness 0.15)) (justify left bottom mirror))
    )
    (fp_text user "${REFERENCE}" (at -0.95 -3.168 90) (layer "B.Fab") hide
        (effects (font (size 0.7 0.7) (thickness 0.15)) (justify left bottom mirror))
    )
    (fp_text user "Author: Antmicro" (at -0.95 -4.169 90) (layer "B.Fab") hide
        (effects (font (size 0.7 0.7) (thickness 0.15)) (justify left bottom mirror))
    )
    (fp_rect (start -0.93 0.47) (end 0.93 -0.47)
      (stroke (width 0.05) (type solid)) (fill none) (layer "B.CrtYd"))
    (fp_rect (start -0.5 0.25) (end 0.5 -0.25)
      (stroke (width 0.15) (type solid)) (fill none) (layer "B.Fab"))
    (pad "1" smd roundrect (at -0.485 0 270) (size 0.59 0.64) (layers "B.Cu" "B.Paste" "B.Mask") (roundrect_rratio 0.25)
      (net 275 "/USB/VBUS") (pintype "passive"))
    (pad "2" smd roundrect (at 0.485 0 270) (size 0.59 0.64) (layers "B.Cu" "B.Paste" "B.Mask") (roundrect_rratio 0.25)
      (net 1 "GND") (pintype "passive"))
  )
	(footprint "kria-k26-devboard-footprints:R_0402_1005Metric" (layer "B.Cu")
    (at 85.3 123.8 180)
    (descr "Resistor SMD 0402")
    (tags "resistor SMD 0402")
    (property "Author" "Antmicro")
    (property "License" "Apache-2.0")
    (property "MPN" "CR0402-FX-2201GLF")
    (property "Manufacturer" "Bourns")
    (property "Sheetfile" "camera.kicad_sch")
    (property "Sheetname" "Camera interface")
    (property "Tolerance" "1%")
    (property "Val" "2k2")
    (property "ki_description" "2k2 resistor in 0402 package with 1% tolerance")
    (attr smd)
    (fp_text reference "R24" (at -3.05 -0.4) (layer "B.SilkS")
        (effects (font (size 0.7 0.7) (thickness 0.15)) (justify left bottom mirror))
    )
    (fp_text value "R_2k2_0402" (at 0 -1.4) (layer "B.Fab") hide
        (effects (font (size 0.7 0.7) (thickness 0.15)) (justify left bottom mirror))
    )
    (fp_text user "${REFERENCE}" (at -0.95 -3.168) (layer "B.Fab") hide
        (effects (font (size 0.7 0.7) (thickness 0.15)) (justify left bottom mirror))
    )
    (fp_text user "License: Apache-2.0" (at -0.95 -5.169) (layer "B.Fab") hide
        (effects (font (size 0.7 0.7) (thickness 0.15)) (justify left bottom mirror))
    )
    (fp_text user "Author: Antmicro" (at -0.95 -4.169) (layer "B.Fab") hide
        (effects (font (size 0.7 0.7) (thickness 0.15)) (justify left bottom mirror))
    )
    (fp_rect (start -0.93 0.47) (end 0.93 -0.47)
      (stroke (width 0.05) (type solid)) (fill none) (layer "B.CrtYd"))
    (fp_rect (start -0.5 0.25) (end 0.5 -0.25)
      (stroke (width 0.15) (type solid)) (fill none) (layer "B.Fab"))
    (pad "1" smd roundrect (at -0.485 0 180) (size 0.59 0.64) (layers "B.Cu" "B.Paste" "B.Mask") (roundrect_rratio 0.25)
      (net 20 "PL_3V3") (pintype "passive"))
    (pad "2" smd roundrect (at 0.485 0 180) (size 0.59 0.64) (layers "B.Cu" "B.Paste" "B.Mask") (roundrect_rratio 0.25)
      (net 410 "/Camera interface/HDA00_CC") (pintype "passive"))
  )
	(footprint "kria-k26-devboard-footprints:C_0402_1005Metric" (layer "B.Cu")
    (at 144.88 117.8)
    (descr "Capacitor SMD 0402")
    (tags "capacitor SMD 0402")
    (property "Author" "Antmicro")
    (property "Dielectric" "X5R")
    (property "License" "Apache-2.0")
    (property "MPN" "GRM155R61H104KE14D")
    (property "Manufacturer" "Murata")
    (property "Sheetfile" "debug.kicad_sch")
    (property "Sheetname" "Debug and JTAG")
    (property "Val" "100n")
    (property "Voltage" "50V")
    (property "ki_description" " ")
    (attr smd)
    (fp_text reference "C141" (at -0.88 0.38 180) (layer "B.SilkS")
        (effects (font (size 0.7 0.7) (thickness 0.15)) (justify left bottom mirror))
    )
    (fp_text value "C_100n_0402" (at 0 -1.4 180) (layer "B.Fab") hide
        (effects (font (size 0.7 0.7) (thickness 0.15)) (justify left bottom mirror))
    )
    (fp_text user "Author: Antmicro" (at -0.932 -4.17 180) (layer "B.Fab") hide
        (effects (font (size 0.7 0.7) (thickness 0.15)) (justify left bottom mirror))
    )
    (fp_text user "License: Apache-2.0" (at -0.932 -5.17 180) (layer "B.Fab") hide
        (effects (font (size 0.7 0.7) (thickness 0.15)) (justify left bottom mirror))
    )
    (fp_text user "${REFERENCE}" (at -0.932 -3.168 180) (layer "B.Fab") hide
        (effects (font (size 0.7 0.7) (thickness 0.15)) (justify left bottom mirror))
    )
    (fp_rect (start -0.94 0.47) (end 0.94 -0.47)
      (stroke (width 0.05) (type solid)) (fill none) (layer "B.CrtYd"))
    (fp_rect (start -0.499 0.249) (end 0.499 -0.249)
      (stroke (width 0.15) (type solid)) (fill none) (layer "B.Fab"))
    (pad "1" smd roundrect (at -0.484 0) (size 0.59 0.64) (layers "B.Cu" "B.Paste" "B.Mask") (roundrect_rratio 0.25)
      (net 132 "/Debug and JTAG/USB_1V2") (pintype "passive"))
    (pad "2" smd roundrect (at 0.484 0) (size 0.59 0.64) (layers "B.Cu" "B.Paste" "B.Mask") (roundrect_rratio 0.25)
      (net 1 "GND") (pintype "passive"))
  )
)
